(kicad_pcb
	(version 20260206)
	(generator "pcbnew")
	(generator_version "10.0")
	(general
		(thickness 1.6)
		(legacy_teardrops no)
	)
	(paper "A4")
	(title_block
		(title "Bryce Canyon_F.DPB_16315-1-OCP.brd")
		(comment 1 "Bryce Canyon / footprints 1741-1747 of 2223")
	)
	(layers
		(0 "F.Cu" signal "TOP")
		(4 "In1.Cu" signal "L2GND")
		(6 "In2.Cu" signal "L3")
		(8 "In3.Cu" signal "L4GND")
		(10 "In4.Cu" signal "L5")
		(12 "In5.Cu" signal "L6VCC")
		(14 "In6.Cu" signal "L7VCC")
		(16 "In7.Cu" signal "L8")
		(18 "In8.Cu" signal "L9GND")
		(20 "In9.Cu" signal "L10")
		(22 "In10.Cu" signal "L11GND")
		(2 "B.Cu" signal "BOTTOM")
		(9 "F.Adhes" user "F.Adhesive")
		(11 "B.Adhes" user "B.Adhesive")
		(13 "F.Paste" user "Package Geometry/Pastemask Top")
		(15 "B.Paste" user "Package Geometry/Pastemask Bottom")
		(5 "F.SilkS" user "Ref Des/Silkscreen Top")
		(7 "B.SilkS" user "Ref Des/Silkscreen Bottom")
		(1 "F.Mask" user "Board Geometry/Soldermask Top")
		(3 "B.Mask" user "Board Geometry/Soldermask Bottom")
		(17 "Dwgs.User" user "User.Drawings")
		(19 "Cmts.User" user "User.Comments")
		(21 "Eco1.User" user "User.Eco1")
		(23 "Eco2.User" user "User.Eco2")
		(25 "Edge.Cuts" user "Board Geometry/Outline")
		(27 "Margin" user)
		(31 "F.CrtYd" user "Package Geometry/Place Bound Top")
		(29 "B.CrtYd" user "Package Geometry/Place Bound Bottom")
		(35 "F.Fab" user "Ref Des/Assembly Top")
		(33 "B.Fab" user "Ref Des/Assembly Bottom")
	)
	(footprint ""
		(layer "F.Cu")
		(at 222.645478 -96.13773 90)
		(property "Reference" "R996"
			(at 0 0 90)
			(layer "F.SilkS")
			(hide yes)
			(effects
				(font
					(size 1.27 1.27)
				)
			)
		)
		(property "Value" "100KR2F-L1-GP"
			(at 0.064008 -3.993896 90)
			(unlocked yes)
			(layer "F.Fab")
			(hide yes)
			(effects
				(font
					(size 1.016 1.016)
					(thickness 0.1524)
				)
			)
		)
		(property "Device Type" "R402H16"
			(at 0.064008 -5.517896 90)
			(unlocked yes)
			(layer "F.Fab")
			(hide yes)
			(effects
				(font
					(size 1.016 1.016)
					(thickness 0.1524)
				)
			)
		)
		(duplicate_pad_numbers_are_jumpers no)
		(fp_line
			(start 0.508 -0.9398)
			(end -0.508 -0.9398)
			(stroke
				(width 0.1524)
				(type default)
			)
			(layer "F.SilkS")
		)
		(fp_line
			(start -0.508 -0.9398)
			(end -0.508 0.9398)
			(stroke
				(width 0.1524)
				(type default)
			)
			(layer "F.SilkS")
		)
		(fp_rect
			(start -0.508 0.9398)
			(end 0.508 -0.9398)
			(stroke
				(width 0)
				(type default)
			)
			(fill no)
			(layer "F.CrtYd")
		)
		(fp_rect
			(start -0.508 0.9398)
			(end 0.508 -0.9398)
			(stroke
				(width 0)
				(type default)
			)
			(fill no)
			(layer "F.Fab")
		)
		(pad "1" smd custom
			(at 0 -0.4445 90)
			(size 0.1397 0.1397)
			(layers "F.Cu" "F.Mask" "F.Paste")
			(net "P3V3_STBY_A")
			(options
				(clearance outline)
				(anchor circle)
			)
			(primitives
				(gr_poly
					(pts
						(arc
							(start -0.1778 -0.2794)
							(mid -0.249642 -0.249642)
							(end -0.2794 -0.1778)
						)
						(arc
							(start -0.2794 0.1778)
							(mid -0.249642 0.249642)
							(end -0.1778 0.2794)
						)
						(arc
							(start 0.1778 0.2794)
							(mid 0.249642 0.249642)
							(end 0.2794 0.1778)
						)
						(arc
							(start 0.2794 -0.1778)
							(mid 0.249642 -0.249642)
							(end 0.1778 -0.2794)
						)
					)
					(width 0)
					(fill yes)
				)
			)
		)
		(pad "2" smd custom
			(at 0 0.4445 90)
			(size 0.1397 0.1397)
			(layers "F.Cu" "F.Mask" "F.Paste")
			(net "COMP_A_PRI_INS_N")
			(options
				(clearance outline)
				(anchor circle)
			)
			(primitives
				(gr_poly
					(pts
						(arc
							(start -0.1778 -0.2794)
							(mid -0.249642 -0.249642)
							(end -0.2794 -0.1778)
						)
						(arc
							(start -0.2794 0.1778)
							(mid -0.249642 0.249642)
							(end -0.1778 0.2794)
						)
						(arc
							(start 0.1778 0.2794)
							(mid 0.249642 0.249642)
							(end 0.2794 0.1778)
						)
						(arc
							(start 0.2794 -0.1778)
							(mid 0.249642 -0.249642)
							(end 0.1778 -0.2794)
						)
					)
					(width 0)
					(fill yes)
				)
			)
		)
	)
	(footprint ""
		(layer "F.Cu")
		(at 410.350208 -294.438324 180)
		(property "Reference" "R310"
			(at 0 0 180)
			(layer "F.SilkS")
			(hide yes)
			(effects
				(font
					(size 1.27 1.27)
				)
			)
		)
		(property "Value" "91R3F-1-GP"
			(at -0.0254 -2.5146 180)
			(unlocked yes)
			(layer "F.Fab")
			(hide yes)
			(effects
				(font
					(size 1.016 1.016)
					(thickness 0.1524)
				)
			)
		)
		(property "Device Type" "R603H22"
			(at -0.0254 -4.0386 180)
			(unlocked yes)
			(layer "F.Fab")
			(hide yes)
			(effects
				(font
					(size 1.016 1.016)
					(thickness 0.1524)
				)
			)
		)
		(duplicate_pad_numbers_are_jumpers no)
		(fp_line
			(start 0.2032 0)
			(end 0.4826 0)
			(stroke
				(width 0.2032)
				(type default)
			)
			(layer "F.SilkS")
		)
		(fp_line
			(start -0.4826 0)
			(end -0.2032 0)
			(stroke
				(width 0.2032)
				(type default)
			)
			(layer "F.SilkS")
		)
		(fp_rect
			(start -0.5842 1.3335)
			(end 0.5842 -1.3335)
			(stroke
				(width 0)
				(type default)
			)
			(fill no)
			(layer "F.CrtYd")
		)
		(fp_rect
			(start -0.5842 1.3335)
			(end 0.5842 -1.3335)
			(stroke
				(width 0)
				(type default)
			)
			(fill no)
			(layer "F.Fab")
		)
		(pad "1" smd custom
			(at 0 -0.762 180)
			(size 0.2159 0.2159)
			(layers "F.Cu" "F.Mask" "F.Paste")
			(net "P5V_B")
			(options
				(clearance outline)
				(anchor circle)
			)
			(primitives
				(gr_poly
					(pts
						(arc
							(start -0.3302 -0.4318)
							(mid -0.402042 -0.402042)
							(end -0.4318 -0.3302)
						)
						(arc
							(start -0.4318 0.3302)
							(mid -0.402042 0.402042)
							(end -0.3302 0.4318)
						)
						(arc
							(start 0.3302 0.4318)
							(mid 0.402042 0.402042)
							(end 0.4318 0.3302)
						)
						(arc
							(start 0.4318 -0.3302)
							(mid 0.402042 -0.402042)
							(end 0.3302 -0.4318)
						)
					)
					(width 0)
					(fill yes)
				)
			)
		)
		(pad "2" smd custom
			(at 0 0.762 180)
			(size 0.2159 0.2159)
			(layers "F.Cu" "F.Mask" "F.Paste")
			(net "DRV_ACT_33")
			(options
				(clearance outline)
				(anchor circle)
			)
			(primitives
				(gr_poly
					(pts
						(arc
							(start -0.3302 -0.4318)
							(mid -0.402042 -0.402042)
							(end -0.4318 -0.3302)
						)
						(arc
							(start -0.4318 0.3302)
							(mid -0.402042 0.402042)
							(end -0.3302 0.4318)
						)
						(arc
							(start 0.3302 0.4318)
							(mid 0.402042 0.402042)
							(end 0.4318 0.3302)
						)
						(arc
							(start 0.4318 -0.3302)
							(mid 0.402042 -0.402042)
							(end 0.3302 -0.4318)
						)
					)
					(width 0)
					(fill yes)
				)
			)
		)
	)
	(footprint ""
		(layer "F.Cu")
		(at 381.36195 -292.194742 90)
		(property "Reference" "R314"
			(at 0 0 90)
			(layer "F.SilkS")
			(hide yes)
			(effects
				(font
					(size 1.27 1.27)
				)
			)
		)
		(property "Value" "10KR2F-2-GP"
			(at 0.064008 -3.993896 90)
			(unlocked yes)
			(layer "F.Fab")
			(hide yes)
			(effects
				(font
					(size 1.016 1.016)
					(thickness 0.1524)
				)
			)
		)
		(property "Device Type" "R402H16"
			(at 0.064008 -5.517896 90)
			(unlocked yes)
			(layer "F.Fab")
			(hide yes)
			(effects
				(font
					(size 1.016 1.016)
					(thickness 0.1524)
				)
			)
		)
		(duplicate_pad_numbers_are_jumpers no)
		(fp_line
			(start 0.508 -0.9398)
			(end -0.508 -0.9398)
			(stroke
				(width 0.1524)
				(type default)
			)
			(layer "F.SilkS")
		)
		(fp_line
			(start -0.508 -0.9398)
			(end -0.508 0.9398)
			(stroke
				(width 0.1524)
				(type default)
			)
			(layer "F.SilkS")
		)
		(fp_rect
			(start -0.508 0.9398)
			(end 0.508 -0.9398)
			(stroke
				(width 0)
				(type default)
			)
			(fill no)
			(layer "F.CrtYd")
		)
		(fp_rect
			(start -0.508 0.9398)
			(end 0.508 -0.9398)
			(stroke
				(width 0)
				(type default)
			)
			(fill no)
			(layer "F.Fab")
		)
		(pad "1" smd custom
			(at 0 -0.4445 90)
			(size 0.1397 0.1397)
			(layers "F.Cu" "F.Mask" "F.Paste")
			(net "P3V3_STBY_A")
			(options
				(clearance outline)
				(anchor circle)
			)
			(primitives
				(gr_poly
					(pts
						(arc
							(start -0.1778 -0.2794)
							(mid -0.249642 -0.249642)
							(end -0.2794 -0.1778)
						)
						(arc
							(start -0.2794 0.1778)
							(mid -0.249642 0.249642)
							(end -0.1778 0.2794)
						)
						(arc
							(start 0.1778 0.2794)
							(mid 0.249642 0.249642)
							(end 0.2794 0.1778)
						)
						(arc
							(start 0.2794 -0.1778)
							(mid 0.249642 -0.249642)
							(end 0.1778 -0.2794)
						)
					)
					(width 0)
					(fill yes)
				)
			)
		)
		(pad "2" smd custom
			(at 0 0.4445 90)
			(size 0.1397 0.1397)
			(layers "F.Cu" "F.Mask" "F.Paste")
			(net "HDD_PRSNT_8")
			(options
				(clearance outline)
				(anchor circle)
			)
			(primitives
				(gr_poly
					(pts
						(arc
							(start -0.1778 -0.2794)
							(mid -0.249642 -0.249642)
							(end -0.2794 -0.1778)
						)
						(arc
							(start -0.2794 0.1778)
							(mid -0.249642 0.249642)
							(end -0.1778 0.2794)
						)
						(arc
							(start 0.1778 0.2794)
							(mid 0.249642 0.249642)
							(end 0.2794 0.1778)
						)
						(arc
							(start 0.2794 -0.1778)
							(mid 0.249642 -0.249642)
							(end 0.1778 -0.2794)
						)
					)
					(width 0)
					(fill yes)
				)
			)
		)
	)
	(footprint ""
		(layer "F.Cu")
		(at 32.463486 -158.660592 90)
		(property "Reference" "C195"
			(at 0 0 90)
			(layer "F.SilkS")
			(hide yes)
			(effects
				(font
					(size 1.27 1.27)
				)
			)
		)
		(property "Value" "SCD01U16V1KX-GP"
			(at -2.8321 -1.7399 90)
			(unlocked yes)
			(layer "F.Fab")
			(hide yes)
			(effects
				(font
					(size 1.016 1.016)
					(thickness 0.1524)
				)
			)
		)
		(property "Device Type" "C0201H13"
			(at -2.8321 -3.2639 90)
			(unlocked yes)
			(layer "F.Fab")
			(hide yes)
			(effects
				(font
					(size 1.016 1.016)
					(thickness 0.1524)
				)
			)
		)
		(duplicate_pad_numbers_are_jumpers no)
		(fp_rect
			(start -0.2794 0.6477)
			(end 0.2794 -0.6477)
			(stroke
				(width 0)
				(type default)
			)
			(fill no)
			(layer "F.CrtYd")
		)
		(fp_rect
			(start -0.2794 0.6477)
			(end 0.2794 -0.6477)
			(stroke
				(width 0)
				(type default)
			)
			(fill no)
			(layer "F.Fab")
		)
		(pad "1" smd custom
			(at 0 -0.2794 90)
			(size 0.0762 0.0762)
			(layers "F.Cu" "F.Mask" "F.Paste")
			(net "SAS_HDD_RX_P12")
			(options
				(clearance outline)
				(anchor circle)
			)
			(primitives
				(gr_poly
					(pts
						(arc
							(start 0.1524 -0.127)
							(mid 0.137521 -0.162921)
							(end 0.1016 -0.1778)
						)
						(arc
							(start -0.1016 -0.1778)
							(mid -0.137521 -0.162921)
							(end -0.1524 -0.127)
						)
						(arc
							(start -0.1524 0.127)
							(mid -0.137521 0.162921)
							(end -0.1016 0.1778)
						)
						(arc
							(start 0.1016 0.1778)
							(mid 0.137521 0.162921)
							(end 0.1524 0.127)
						)
					)
					(width 0)
					(fill yes)
				)
			)
		)
		(pad "2" smd custom
			(at 0 0.2794 90)
			(size 0.0762 0.0762)
			(layers "F.Cu" "F.Mask" "F.Paste")
			(net "PHY_SCC_A_TO_DRV_A_12_DP")
			(options
				(clearance outline)
				(anchor circle)
			)
			(primitives
				(gr_poly
					(pts
						(arc
							(start 0.1524 -0.127)
							(mid 0.137521 -0.162921)
							(end 0.1016 -0.1778)
						)
						(arc
							(start -0.1016 -0.1778)
							(mid -0.137521 -0.162921)
							(end -0.1524 -0.127)
						)
						(arc
							(start -0.1524 0.127)
							(mid -0.137521 0.162921)
							(end -0.1016 0.1778)
						)
						(arc
							(start 0.1016 0.1778)
							(mid 0.137521 0.162921)
							(end 0.1524 0.127)
						)
					)
					(width 0)
					(fill yes)
				)
			)
		)
	)
	(footprint ""
		(layer "F.Cu")
		(at 17.145 -127.254)
		(property "Reference" "R273"
			(at 0 0 0)
			(layer "F.SilkS")
			(hide yes)
			(effects
				(font
					(size 1.27 1.27)
				)
			)
		)
		(property "Value" "130R3F-GP"
			(at -0.0254 -2.5146 0)
			(unlocked yes)
			(layer "F.Fab")
			(hide yes)
			(effects
				(font
					(size 1.016 1.016)
					(thickness 0.1524)
				)
			)
		)
		(property "Device Type" "R603H22"
			(at -0.0254 -4.0386 0)
			(unlocked yes)
			(layer "F.Fab")
			(hide yes)
			(effects
				(font
					(size 1.016 1.016)
					(thickness 0.1524)
				)
			)
		)
		(duplicate_pad_numbers_are_jumpers no)
		(fp_line
			(start -0.4826 0)
			(end -0.2032 0)
			(stroke
				(width 0.2032)
				(type default)
			)
			(layer "F.SilkS")
		)
		(fp_line
			(start 0.2032 0)
			(end 0.4826 0)
			(stroke
				(width 0.2032)
				(type default)
			)
			(layer "F.SilkS")
		)
		(fp_rect
			(start -0.5842 1.3335)
			(end 0.5842 -1.3335)
			(stroke
				(width 0)
				(type default)
			)
			(fill no)
			(layer "F.CrtYd")
		)
		(fp_rect
			(start -0.5842 1.3335)
			(end 0.5842 -1.3335)
			(stroke
				(width 0)
				(type default)
			)
			(fill no)
			(layer "F.Fab")
		)
		(pad "1" smd custom
			(at 0 -0.762)
			(size 0.2159 0.2159)
			(layers "F.Cu" "F.Mask" "F.Paste")
			(net "P5V_A_1")
			(options
				(clearance outline)
				(anchor circle)
			)
			(primitives
				(gr_poly
					(pts
						(arc
							(start -0.3302 -0.4318)
							(mid -0.402042 -0.402042)
							(end -0.4318 -0.3302)
						)
						(arc
							(start -0.4318 0.3302)
							(mid -0.402042 0.402042)
							(end -0.3302 0.4318)
						)
						(arc
							(start 0.3302 0.4318)
							(mid 0.402042 0.402042)
							(end 0.4318 0.3302)
						)
						(arc
							(start 0.4318 -0.3302)
							(mid 0.402042 -0.402042)
							(end 0.3302 -0.4318)
						)
					)
					(width 0)
					(fill yes)
				)
			)
		)
		(pad "2" smd custom
			(at 0 0.762)
			(size 0.2159 0.2159)
			(layers "F.Cu" "F.Mask" "F.Paste")
			(net "FLT_HDD12")
			(options
				(clearance outline)
				(anchor circle)
			)
			(primitives
				(gr_poly
					(pts
						(arc
							(start -0.3302 -0.4318)
							(mid -0.402042 -0.402042)
							(end -0.4318 -0.3302)
						)
						(arc
							(start -0.4318 0.3302)
							(mid -0.402042 0.402042)
							(end -0.3302 0.4318)
						)
						(arc
							(start 0.3302 0.4318)
							(mid 0.402042 0.402042)
							(end 0.4318 0.3302)
						)
						(arc
							(start 0.4318 -0.3302)
							(mid 0.402042 -0.402042)
							(end 0.3302 -0.4318)
						)
					)
					(width 0)
					(fill yes)
				)
			)
		)
	)
	(footprint ""
		(layer "F.Cu")
		(at 356.289102 -47.749968 -90)
		(property "Reference" "VIA72"
			(at 0 0 270)
			(layer "F.SilkS")
			(hide yes)
			(effects
				(font
					(size 1.27 1.27)
				)
			)
		)
		(property "Value" "100OHM-8L-1D6MM-L18L16-GP"
			(at -3.7211 -4.5085 270)
			(unlocked yes)
			(layer "F.Fab")
			(hide yes)
			(effects
				(font
					(size 1.016 1.016)
					(thickness 0.1524)
				)
			)
		)
		(property "Device Type" "VIA-PCIE-4P-394076"
			(at -3.7211 -6.0325 270)
			(unlocked yes)
			(layer "F.Fab")
			(hide yes)
			(effects
				(font
					(size 1.016 1.016)
					(thickness 0.1524)
				)
			)
		)
		(duplicate_pad_numbers_are_jumpers no)
		(fp_rect
			(start -1.9685 0.381)
			(end 1.9685 -0.381)
			(stroke
				(width 0)
				(type default)
			)
			(fill no)
			(layer "F.CrtYd")
		)
		(fp_rect
			(start -1.9685 0.381)
			(end 1.9685 -0.381)
			(stroke
				(width 0)
				(type default)
			)
			(fill no)
			(layer "F.Fab")
		)
		(pad "1" thru_hole circle
			(at -1.5875 0 270)
			(size 0.508 0.508)
			(drill 0.254)
			(layers "*.Cu" "*.Mask")
			(remove_unused_layers no)
			(net "GND")
			(clearance 0.127)
			(thermal_gap 0.127)
		)
		(pad "2" thru_hole circle
			(at -0.5715 0 270)
			(size 0.508 0.508)
			(drill 0.254)
			(layers "*.Cu" "*.Mask")
			(remove_unused_layers no)
			(net "PHY_DRV_A_TO_SCC_A_31_DP")
			(clearance 0.127)
			(thermal_gap 0.127)
		)
		(pad "3" thru_hole circle
			(at 0.5715 0 270)
			(size 0.508 0.508)
			(drill 0.254)
			(layers "*.Cu" "*.Mask")
			(remove_unused_layers no)
			(net "PHY_DRV_A_TO_SCC_A_31_DN")
			(clearance 0.127)
			(thermal_gap 0.127)
		)
		(pad "4" thru_hole circle
			(at 1.5875 0 270)
			(size 0.508 0.508)
			(drill 0.254)
			(layers "*.Cu" "*.Mask")
			(remove_unused_layers no)
			(net "GND")
			(clearance 0.127)
			(thermal_gap 0.127)
		)
	)
	(footprint ""
		(layer "F.Cu")
		(at 38.100254 -303.904396)
		(property "Reference" "Q252"
			(at 0 0 0)
			(layer "F.SilkS")
			(hide yes)
			(effects
				(font
					(size 1.27 1.27)
				)
			)
		)
		(property "Value" "2N7002K-2-GP"
			(at 0.127 -8.9662 0)
			(unlocked yes)
			(layer "F.Fab")
			(hide yes)
			(effects
				(font
					(size 1.016 1.016)
					(thickness 0.1524)
				)
			)
		)
		(property "Device Type" "SOT23DGS2D4H44"
			(at 0.127 -10.4902 0)
			(unlocked yes)
			(layer "F.Fab")
			(hide yes)
			(effects
				(font
					(size 1.016 1.016)
					(thickness 0.1524)
				)
			)
		)
		(duplicate_pad_numbers_are_jumpers no)
		(fp_line
			(start -1.651 -1.778)
			(end -1.651 1.778)
			(stroke
				(width 0.1524)
				(type default)
			)
			(layer "F.SilkS")
		)
		(fp_line
			(start -1.651 1.778)
			(end 1.651 1.778)
			(stroke
				(width 0.1524)
				(type default)
			)
			(layer "F.SilkS")
		)
		(fp_line
			(start 1.651 -1.778)
			(end -1.651 -1.778)
			(stroke
				(width 0.1524)
				(type default)
			)
			(layer "F.SilkS")
		)
		(fp_line
			(start 1.651 1.778)
			(end 1.651 -1.778)
			(stroke
				(width 0.1524)
				(type default)
			)
			(layer "F.SilkS")
		)
		(fp_poly
			(pts
				(xy -1.778 1.8796) (xy -1.778 -1.8796) (xy 1.778 -1.8796) (xy 1.778 1.8796)
			)
			(stroke
				(width 0)
				(type default)
			)
			(fill no)
			(layer "F.CrtYd")
		)
		(fp_poly
			(pts
				(xy -1.778 1.8796) (xy -1.778 -1.8796) (xy 1.778 -1.8796) (xy 1.778 1.8796)
			)
			(stroke
				(width 0)
				(type default)
			)
			(fill no)
			(layer "F.Fab")
		)
		(pad "D" smd custom
			(at 0 -0.9525)
			(size 0.1905 0.1905)
			(layers "F.Cu" "F.Mask" "F.Paste")
			(net "FLT_HDD25_N")
			(options
				(clearance outline)
				(anchor circle)
			)
			(primitives
				(gr_poly
					(pts
						(arc
							(start -0.1778 0.5715)
							(mid -0.321484 0.511984)
							(end -0.381 0.3683)
						)
						(arc
							(start -0.381 -0.3683)
							(mid -0.321484 -0.511984)
							(end -0.1778 -0.5715)
						)
						(arc
							(start 0.1778 -0.5715)
							(mid 0.321484 -0.511984)
							(end 0.381 -0.3683)
						)
						(arc
							(start 0.381 0.3683)
							(mid 0.321484 0.511984)
							(end 0.1778 0.5715)
						)
					)
					(width 0)
					(fill yes)
				)
			)
		)
		(pad "G" smd custom
			(at -0.98425 0.9525)
			(size 0.1905 0.1905)
			(layers "F.Cu" "F.Mask" "F.Paste")
			(net "DRIVE_B_25_FLT_LED")
			(options
				(clearance outline)
				(anchor circle)
			)
			(primitives
				(gr_poly
					(pts
						(arc
							(start -0.1778 0.5715)
							(mid -0.321484 0.511984)
							(end -0.381 0.3683)
						)
						(arc
							(start -0.381 -0.3683)
							(mid -0.321484 -0.511984)
							(end -0.1778 -0.5715)
						)
						(arc
							(start 0.1778 -0.5715)
							(mid 0.321484 -0.511984)
							(end 0.381 -0.3683)
						)
						(arc
							(start 0.381 0.3683)
							(mid 0.321484 0.511984)
							(end 0.1778 0.5715)
						)
					)
					(width 0)
					(fill yes)
				)
			)
		)
		(pad "S" smd custom
			(at 0.98425 0.9525)
			(size 0.1905 0.1905)
			(layers "F.Cu" "F.Mask" "F.Paste")
			(net "GND")
			(options
				(clearance outline)
				(anchor circle)
			)
			(primitives
				(gr_poly
					(pts
						(arc
							(start -0.1778 0.5715)
							(mid -0.321484 0.511984)
							(end -0.381 0.3683)
						)
						(arc
							(start -0.381 -0.3683)
							(mid -0.321484 -0.511984)
							(end -0.1778 -0.5715)
						)
						(arc
							(start 0.1778 -0.5715)
							(mid 0.321484 -0.511984)
							(end 0.381 -0.3683)
						)
						(arc
							(start 0.381 0.3683)
							(mid 0.321484 0.511984)
							(end 0.1778 0.5715)
						)
					)
					(width 0)
					(fill yes)
				)
			)
		)
	)
)
